(kicad_pcb
	(version 20241229)
	(generator "pcbnew")
	(generator_version "9.0")
	(general
		(thickness 1.61)
		(legacy_teardrops no)
	)
	(paper "A3")
	(title_block
		(title "SO-DIMM DDR5 Tester")
		(date "2025-11-26")
		(rev "1.3.0")
		(comment 9 "footprints 510-515 of 627")
	)
	(layers
		(0 "F.Cu" signal)
		(4 "In1.Cu" power)
		(6 "In2.Cu" mixed)
		(8 "In3.Cu" power)
		(10 "In4.Cu" mixed)
		(12 "In5.Cu" power)
		(14 "In6.Cu" mixed)
		(16 "In7.Cu" power)
		(18 "In8.Cu" power)
		(20 "In9.Cu" mixed)
		(22 "In10.Cu" power)
		(2 "B.Cu" signal)
		(9 "F.Adhes" user "F.Adhesive")
		(11 "B.Adhes" user "B.Adhesive")
		(13 "F.Paste" user)
		(15 "B.Paste" user)
		(5 "F.SilkS" user "F.Silkscreen")
		(7 "B.SilkS" user "B.Silkscreen")
		(1 "F.Mask" user)
		(3 "B.Mask" user)
		(17 "Dwgs.User" user "User.Drawings")
		(19 "Cmts.User" user "User.Comments")
		(21 "Eco1.User" user "User.Eco1")
		(23 "Eco2.User" user "User.Eco2")
		(25 "Edge.Cuts" user)
		(27 "Margin" user)
		(31 "F.CrtYd" user "F.Courtyard")
		(29 "B.CrtYd" user "B.Courtyard")
		(35 "F.Fab" user)
		(33 "B.Fab" user)
	)
	(footprint "antmicro-footprints:C_0402_1005Metric"
		(layer "B.Cu")
		(at 141.85 159.6)
		(descr "Capacitor SMD 0402")
		(tags "capacitor SMD 0402")
		(property "Reference" "C167"
			(at 0 0.699 180)
			(layer "B.SilkS")
			(hide yes)
			(effects
				(font
					(size 0.7 0.7)
					(thickness 0.15)
				)
				(justify left bottom mirror)
			)
		)
		(property "Value" "C_100n_0402"
			(at -1.022927 -2.155213 180)
			(layer "B.Fab")
			(effects
				(font
					(size 0.7 0.7)
					(thickness 0.15)
				)
				(justify left bottom mirror)
			)
		)
		(property "Datasheet" "https://www.murata.com/products/productdetail?partno=GRM155R61H104KE14%23"
			(at 0 0 0)
			(layer "F.Fab")
			(hide yes)
			(effects
				(font
					(size 1.27 1.27)
					(thickness 0.15)
				)
			)
		)
		(property "Author" "Antmicro"
			(at 0 0 0)
			(layer "B.Fab")
			(hide yes)
			(effects
				(font
					(size 1 1)
					(thickness 0.15)
				)
				(justify mirror)
			)
		)
		(property "Dielectric" "X5R"
			(at 0 0 0)
			(layer "B.Fab")
			(hide yes)
			(effects
				(font
					(size 1 1)
					(thickness 0.15)
				)
				(justify mirror)
			)
		)
		(property "License" "Apache-2.0"
			(at 0 0 0)
			(layer "B.Fab")
			(hide yes)
			(effects
				(font
					(size 1 1)
					(thickness 0.15)
				)
				(justify mirror)
			)
		)
		(property "MPN" "GRM155R61H104KE14D"
			(at 0 0 0)
			(layer "B.Fab")
			(hide yes)
			(effects
				(font
					(size 1 1)
					(thickness 0.15)
				)
				(justify mirror)
			)
		)
		(property "Manufacturer" "Murata"
			(at 0 0 0)
			(layer "B.Fab")
			(hide yes)
			(effects
				(font
					(size 1 1)
					(thickness 0.15)
				)
				(justify mirror)
			)
		)
		(property "Val" "100n"
			(at 0 0 0)
			(layer "B.Fab")
			(hide yes)
			(effects
				(font
					(size 1 1)
					(thickness 0.15)
				)
				(justify mirror)
			)
		)
		(property "Voltage" "50V"
			(at 0 0 0)
			(layer "B.Fab")
			(hide yes)
			(effects
				(font
					(size 1 1)
					(thickness 0.15)
				)
				(justify mirror)
			)
		)
		(sheetname "/FPGA banks HP/")
		(sheetfile "fpga-banks-32-34.kicad_sch")
		(attr smd)
		(fp_rect
			(start -0.9659 0.481258)
			(end 0.9649 -0.458742)
			(stroke
				(width 0.05)
				(type solid)
			)
			(fill no)
			(layer "B.CrtYd")
		)
		(fp_line
			(start -0.499 -0.248)
			(end -0.499 0.25)
			(stroke
				(width 0.15)
				(type solid)
			)
			(layer "B.Fab")
		)
		(fp_line
			(start -0.499 0.25)
			(end 0.499 0.25)
			(stroke
				(width 0.15)
				(type solid)
			)
			(layer "B.Fab")
		)
		(fp_line
			(start 0.499 -0.248)
			(end -0.499 -0.248)
			(stroke
				(width 0.15)
				(type solid)
			)
			(layer "B.Fab")
		)
		(fp_line
			(start 0.499 0.25)
			(end 0.499 -0.248)
			(stroke
				(width 0.15)
				(type solid)
			)
			(layer "B.Fab")
		)
		(pad "1" smd roundrect
			(at -0.484 0)
			(size 0.59 0.64)
			(layers "B.Cu" "B.Mask" "B.Paste")
			(roundrect_rratio 0.25)
			(net 10 "/FPGA banks HP/VREF")
			(pintype "passive")
		)
		(pad "2" smd roundrect
			(at 0.484 0)
			(size 0.59 0.64)
			(layers "B.Cu" "B.Mask" "B.Paste")
			(roundrect_rratio 0.25)
			(net 1 "GND")
			(pintype "passive")
		)
	)
	(footprint "antmicro-footprints:C_0402_1005Metric"
		(layer "B.Cu")
		(at 141.875501 172.301)
		(descr "Capacitor SMD 0402 (1005 Metric), square (rectangular) end terminal, IPC_7351 nominal, (Body size source: IPC-SM-782 page 76, https://www.pcb-3d.com/wordpress/wp-content/uploads/ipc-sm-782a_amendment_1_and_2.pdf)")
		(tags "capacitor 0402")
		(property "Reference" "C64"
			(at 0 1.17 180)
			(layer "B.SilkS")
			(hide yes)
			(effects
				(font
					(size 0.7 0.7)
					(thickness 0.15)
				)
				(justify left bottom mirror)
			)
		)
		(property "Value" "C_100n_0402"
			(at 0 -1.169 180)
			(layer "B.Fab")
			(effects
				(font
					(size 0.7 0.7)
					(thickness 0.15)
				)
				(justify left bottom mirror)
			)
		)
		(property "Datasheet" "https://www.murata.com/products/productdetail?partno=GRM155R61H104KE14%23"
			(at 0 0 0)
			(layer "F.Fab")
			(hide yes)
			(effects
				(font
					(size 1.27 1.27)
					(thickness 0.15)
				)
			)
		)
		(property "Author" "Antmicro"
			(at 0 0 0)
			(layer "B.Fab")
			(hide yes)
			(effects
				(font
					(size 1 1)
					(thickness 0.15)
				)
				(justify mirror)
			)
		)
		(property "Dielectric" "X5R"
			(at 0 0 0)
			(layer "B.Fab")
			(hide yes)
			(effects
				(font
					(size 1 1)
					(thickness 0.15)
				)
				(justify mirror)
			)
		)
		(property "License" "Apache-2.0"
			(at 0 0 0)
			(layer "B.Fab")
			(hide yes)
			(effects
				(font
					(size 1 1)
					(thickness 0.15)
				)
				(justify mirror)
			)
		)
		(property "MPN" "GRM155R61H104KE14D"
			(at 0 0 0)
			(layer "B.Fab")
			(hide yes)
			(effects
				(font
					(size 1 1)
					(thickness 0.15)
				)
				(justify mirror)
			)
		)
		(property "Manufacturer" "Murata"
			(at 0 0 0)
			(layer "B.Fab")
			(hide yes)
			(effects
				(font
					(size 1 1)
					(thickness 0.15)
				)
				(justify mirror)
			)
		)
		(property "Val" "100n"
			(at 0 0 0)
			(layer "B.Fab")
			(hide yes)
			(effects
				(font
					(size 1 1)
					(thickness 0.15)
				)
				(justify mirror)
			)
		)
		(property "Voltage" "50V"
			(at 0 0 0)
			(layer "B.Fab")
			(hide yes)
			(effects
				(font
					(size 1 1)
					(thickness 0.15)
				)
				(justify mirror)
			)
		)
		(sheetname "/FPGA power/")
		(sheetfile "fpga-power.kicad_sch")
		(attr smd)
		(fp_rect
			(start -0.9656 0.4572)
			(end 0.9652 -0.4828)
			(stroke
				(width 0.05)
				(type solid)
			)
			(fill no)
			(layer "B.CrtYd")
		)
		(fp_line
			(start -0.5 -0.248)
			(end -0.5 0.25)
			(stroke
				(width 0.15)
				(type solid)
			)
			(layer "B.Fab")
		)
		(fp_line
			(start -0.5 0.25)
			(end 0.498 0.25)
			(stroke
				(width 0.15)
				(type solid)
			)
			(layer "B.Fab")
		)
		(fp_line
			(start 0.498 -0.248)
			(end -0.5 -0.248)
			(stroke
				(width 0.15)
				(type solid)
			)
			(layer "B.Fab")
		)
		(fp_line
			(start 0.498 0.25)
			(end 0.498 -0.248)
			(stroke
				(width 0.15)
				(type solid)
			)
			(layer "B.Fab")
		)
		(pad "1" smd roundrect
			(at -0.5 0 270)
			(size 0.6 0.6)
			(layers "B.Cu" "B.Mask" "B.Paste")
			(roundrect_rratio 0.25)
			(net 1 "GND")
			(pintype "passive")
		)
		(pad "2" smd roundrect
			(at 0.498 0)
			(size 0.6 0.6)
			(layers "B.Cu" "B.Mask" "B.Paste")
			(roundrect_rratio 0.25)
			(net 188 "+1V8")
			(pintype "passive")
		)
	)
	(footprint "antmicro-footprints:TP_SMD_1mm"
		(layer "B.Cu")
		(at 177.74 165.88 180)
		(property "Reference" "TP55"
			(at 0.58 -0.43 0)
			(layer "B.SilkS")
			(effects
				(font
					(size 0.7 0.7)
					(thickness 0.15)
				)
				(justify left bottom mirror)
			)
		)
		(property "Value" "TP_1mm_SMD"
			(at 0 -1.4 0)
			(layer "B.Fab")
			(effects
				(font
					(size 0.7 0.7)
					(thickness 0.15)
				)
				(justify left bottom mirror)
			)
		)
		(property "MPN" ""
			(at 0 0 0)
			(unlocked yes)
			(layer "B.Fab")
			(hide yes)
			(effects
				(font
					(size 1 1)
					(thickness 0.15)
				)
				(justify mirror)
			)
		)
		(property "Manufacturer" ""
			(at 0 0 0)
			(unlocked yes)
			(layer "B.Fab")
			(hide yes)
			(effects
				(font
					(size 1 1)
					(thickness 0.15)
				)
				(justify mirror)
			)
		)
		(property "Author" "Antmicro"
			(at 0 0 0)
			(unlocked yes)
			(layer "B.Fab")
			(hide yes)
			(effects
				(font
					(size 1 1)
					(thickness 0.15)
				)
				(justify mirror)
			)
		)
		(property "License" "Apache-2.0"
			(at 0 0 0)
			(unlocked yes)
			(layer "B.Fab")
			(hide yes)
			(effects
				(font
					(size 1 1)
					(thickness 0.15)
				)
				(justify mirror)
			)
		)
		(sheetname "/Supply/")
		(sheetfile "supply.kicad_sch")
		(attr exclude_from_pos_files)
		(fp_circle
			(center 0 0)
			(end 0.6 0)
			(stroke
				(width 0.05)
				(type default)
			)
			(fill no)
			(layer "B.CrtYd")
		)
		(fp_text user "Author: Antmicro"
			(at -0.5 -4 0)
			(layer "B.Fab")
			(effects
				(font
					(size 0.7 0.7)
					(thickness 0.15)
				)
				(justify left bottom mirror)
			)
		)
		(fp_text user "${REFERENCE}"
			(at -0.5 -2.8 0)
			(layer "B.Fab")
			(effects
				(font
					(size 0.7 0.7)
					(thickness 0.15)
				)
				(justify left bottom mirror)
			)
		)
		(fp_text user "License: Apache-2.0"
			(at -0.5 -5.2 0)
			(layer "B.Fab")
			(effects
				(font
					(size 0.7 0.7)
					(thickness 0.15)
				)
				(justify left bottom mirror)
			)
		)
		(pad "1" smd circle
			(at 0 0 180)
			(size 1 1)
			(layers "B.Cu" "B.Mask")
			(net 297 "/Supply/PWR_SCL_2")
			(pinfunction "1")
			(pintype "passive")
		)
	)
	(footprint "antmicro-footprints:C_0402_1005Metric"
		(layer "B.Cu")
		(at 144.875501 172.301)
		(descr "Capacitor SMD 0402 (1005 Metric), square (rectangular) end terminal, IPC_7351 nominal, (Body size source: IPC-SM-782 page 76, https://www.pcb-3d.com/wordpress/wp-content/uploads/ipc-sm-782a_amendment_1_and_2.pdf)")
		(tags "capacitor 0402")
		(property "Reference" "C81"
			(at 0 1.17 180)
			(layer "B.SilkS")
			(hide yes)
			(effects
				(font
					(size 0.7 0.7)
					(thickness 0.15)
				)
				(justify left bottom mirror)
			)
		)
		(property "Value" "C_100n_0402"
			(at 0 -1.169 180)
			(layer "B.Fab")
			(effects
				(font
					(size 0.7 0.7)
					(thickness 0.15)
				)
				(justify left bottom mirror)
			)
		)
		(property "Datasheet" "https://www.murata.com/products/productdetail?partno=GRM155R61H104KE14%23"
			(at 0 0 0)
			(layer "F.Fab")
			(hide yes)
			(effects
				(font
					(size 1.27 1.27)
					(thickness 0.15)
				)
			)
		)
		(property "Author" "Antmicro"
			(at 0 0 0)
			(layer "B.Fab")
			(hide yes)
			(effects
				(font
					(size 1 1)
					(thickness 0.15)
				)
				(justify mirror)
			)
		)
		(property "Dielectric" "X5R"
			(at 0 0 0)
			(layer "B.Fab")
			(hide yes)
			(effects
				(font
					(size 1 1)
					(thickness 0.15)
				)
				(justify mirror)
			)
		)
		(property "License" "Apache-2.0"
			(at 0 0 0)
			(layer "B.Fab")
			(hide yes)
			(effects
				(font
					(size 1 1)
					(thickness 0.15)
				)
				(justify mirror)
			)
		)
		(property "MPN" "GRM155R61H104KE14D"
			(at 0 0 0)
			(layer "B.Fab")
			(hide yes)
			(effects
				(font
					(size 1 1)
					(thickness 0.15)
				)
				(justify mirror)
			)
		)
		(property "Manufacturer" "Murata"
			(at 0 0 0)
			(layer "B.Fab")
			(hide yes)
			(effects
				(font
					(size 1 1)
					(thickness 0.15)
				)
				(justify mirror)
			)
		)
		(property "Val" "100n"
			(at 0 0 0)
			(layer "B.Fab")
			(hide yes)
			(effects
				(font
					(size 1 1)
					(thickness 0.15)
				)
				(justify mirror)
			)
		)
		(property "Voltage" "50V"
			(at 0 0 0)
			(layer "B.Fab")
			(hide yes)
			(effects
				(font
					(size 1 1)
					(thickness 0.15)
				)
				(justify mirror)
			)
		)
		(sheetname "/FPGA power/")
		(sheetfile "fpga-power.kicad_sch")
		(attr smd)
		(fp_rect
			(start -0.9656 0.4572)
			(end 0.9652 -0.4828)
			(stroke
				(width 0.05)
				(type solid)
			)
			(fill no)
			(layer "B.CrtYd")
		)
		(fp_line
			(start -0.5 -0.248)
			(end -0.5 0.25)
			(stroke
				(width 0.15)
				(type solid)
			)
			(layer "B.Fab")
		)
		(fp_line
			(start -0.5 0.25)
			(end 0.498 0.25)
			(stroke
				(width 0.15)
				(type solid)
			)
			(layer "B.Fab")
		)
		(fp_line
			(start 0.498 -0.248)
			(end -0.5 -0.248)
			(stroke
				(width 0.15)
				(type solid)
			)
			(layer "B.Fab")
		)
		(fp_line
			(start 0.498 0.25)
			(end 0.498 -0.248)
			(stroke
				(width 0.15)
				(type solid)
			)
			(layer "B.Fab")
		)
		(pad "1" smd roundrect
			(at -0.5 0 270)
			(size 0.6 0.6)
			(layers "B.Cu" "B.Mask" "B.Paste")
			(roundrect_rratio 0.25)
			(net 1 "GND")
			(pintype "passive")
		)
		(pad "2" smd roundrect
			(at 0.498 0)
			(size 0.6 0.6)
			(layers "B.Cu" "B.Mask" "B.Paste")
			(roundrect_rratio 0.25)
			(net 188 "+1V8")
			(pintype "passive")
		)
	)
	(footprint "antmicro-footprints:R_0402_1005Metric"
		(layer "B.Cu")
		(at 134.75 142.4 90)
		(descr "Resistor SMD 0402")
		(tags "resistor SMD 0402")
		(property "Reference" "R26"
			(at 3.05 0.35 270)
			(layer "B.SilkS")
			(effects
				(font
					(size 0.7 0.7)
					(thickness 0.15)
				)
				(justify left bottom mirror)
			)
		)
		(property "Value" "R_0R_0402"
			(at -1.011843 -1.772047 270)
			(layer "B.Fab")
			(effects
				(font
					(size 0.7 0.7)
					(thickness 0.15)
				)
				(justify left bottom mirror)
			)
		)
		(property "Datasheet" "https://industrial.panasonic.com/cdbs/www-data/pdf/RDA0000/AOA0000C301.pdf"
			(at 0 0 90)
			(layer "F.Fab")
			(hide yes)
			(effects
				(font
					(size 1.27 1.27)
					(thickness 0.15)
				)
			)
		)
		(property "Author" "Antmicro"
			(at 277.15 7.65 0)
			(layer "B.Fab")
			(hide yes)
			(effects
				(font
					(size 1 1)
					(thickness 0.15)
				)
				(justify mirror)
			)
		)
		(property "Current" "1A"
			(at 277.15 7.65 0)
			(layer "B.Fab")
			(hide yes)
			(effects
				(font
					(size 1 1)
					(thickness 0.15)
				)
				(justify mirror)
			)
		)
		(property "License" "Apache-2.0"
			(at 277.15 7.65 0)
			(layer "B.Fab")
			(hide yes)
			(effects
				(font
					(size 1 1)
					(thickness 0.15)
				)
				(justify mirror)
			)
		)
		(property "MPN" "ERJ2GE0R00X"
			(at 277.15 7.65 0)
			(layer "B.Fab")
			(hide yes)
			(effects
				(font
					(size 1 1)
					(thickness 0.15)
				)
				(justify mirror)
			)
		)
		(property "Manufacturer" "Panasonic"
			(at 277.15 7.65 0)
			(layer "B.Fab")
			(hide yes)
			(effects
				(font
					(size 1 1)
					(thickness 0.15)
				)
				(justify mirror)
			)
		)
		(property "Tolerance" ""
			(at 277.15 7.65 0)
			(layer "B.Fab")
			(hide yes)
			(effects
				(font
					(size 1 1)
					(thickness 0.15)
				)
				(justify mirror)
			)
		)
		(property "Val" "0R"
			(at 277.15 7.65 0)
			(layer "B.Fab")
			(hide yes)
			(effects
				(font
					(size 1 1)
					(thickness 0.15)
				)
				(justify mirror)
			)
		)
		(sheetname "/DDR5 SODIMM/")
		(sheetfile "ddr5-sodimm.kicad_sch")
		(attr exclude_from_pos_files exclude_from_bom dnp)
		(fp_rect
			(start -0.93 0.47)
			(end 0.93 -0.47)
			(stroke
				(width 0.05)
				(type solid)
			)
			(fill no)
			(layer "B.CrtYd")
		)
		(fp_rect
			(start -0.5 0.25)
			(end 0.5 -0.25)
			(stroke
				(width 0.15)
				(type solid)
			)
			(fill no)
			(layer "B.Fab")
		)
		(pad "1" smd roundrect
			(at -0.485 0 90)
			(size 0.59 0.64)
			(layers "B.Cu" "B.Mask" "B.Paste")
			(roundrect_rratio 0.25)
			(net 1 "GND")
			(pintype "passive")
		)
		(pad "2" smd roundrect
			(at 0.485 0 90)
			(size 0.59 0.64)
			(layers "B.Cu" "B.Mask" "B.Paste")
			(roundrect_rratio 0.25)
			(net 140 "/DDR5 SODIMM/VSS_DET1")
			(pintype "passive")
		)
	)
	(footprint "antmicro-footprints:C_0402_1005Metric"
		(layer "B.Cu")
		(at 131.375501 165.801 -90)
		(descr "Capacitor SMD 0402 (1005 Metric), square (rectangular) end terminal, IPC_7351 nominal, (Body size source: IPC-SM-782 page 76, https://www.pcb-3d.com/wordpress/wp-content/uploads/ipc-sm-782a_amendment_1_and_2.pdf)")
		(tags "capacitor 0402")
		(property "Reference" "C40"
			(at 0 1.17 90)
			(layer "B.SilkS")
			(hide yes)
			(effects
				(font
					(size 0.7 0.7)
					(thickness 0.15)
				)
				(justify left bottom mirror)
			)
		)
		(property "Value" "C_100n_0402"
			(at 0 -1.169 90)
			(layer "B.Fab")
			(effects
				(font
					(size 0.7 0.7)
					(thickness 0.15)
				)
				(justify left bottom mirror)
			)
		)
		(property "Datasheet" "https://www.murata.com/products/productdetail?partno=GRM155R61H104KE14%23"
			(at 0 0 270)
			(layer "F.Fab")
			(hide yes)
			(effects
				(font
					(size 1.27 1.27)
					(thickness 0.15)
				)
			)
		)
		(property "Author" "Antmicro"
			(at -34.425499 297.176501 0)
			(layer "B.Fab")
			(hide yes)
			(effects
				(font
					(size 1 1)
					(thickness 0.15)
				)
				(justify mirror)
			)
		)
		(property "Dielectric" "X5R"
			(at -34.425499 297.176501 0)
			(layer "B.Fab")
			(hide yes)
			(effects
				(font
					(size 1 1)
					(thickness 0.15)
				)
				(justify mirror)
			)
		)
		(property "License" "Apache-2.0"
			(at -34.425499 297.176501 0)
			(layer "B.Fab")
			(hide yes)
			(effects
				(font
					(size 1 1)
					(thickness 0.15)
				)
				(justify mirror)
			)
		)
		(property "MPN" "GRM155R61H104KE14D"
			(at -34.425499 297.176501 0)
			(layer "B.Fab")
			(hide yes)
			(effects
				(font
					(size 1 1)
					(thickness 0.15)
				)
				(justify mirror)
			)
		)
		(property "Manufacturer" "Murata"
			(at -34.425499 297.176501 0)
			(layer "B.Fab")
			(hide yes)
			(effects
				(font
					(size 1 1)
					(thickness 0.15)
				)
				(justify mirror)
			)
		)
		(property "Val" "100n"
			(at -34.425499 297.176501 0)
			(layer "B.Fab")
			(hide yes)
			(effects
				(font
					(size 1 1)
					(thickness 0.15)
				)
				(justify mirror)
			)
		)
		(property "Voltage" "50V"
			(at -34.425499 297.176501 0)
			(layer "B.Fab")
			(hide yes)
			(effects
				(font
					(size 1 1)
					(thickness 0.15)
				)
				(justify mirror)
			)
		)
		(sheetname "/FPGA power/")
		(sheetfile "fpga-power.kicad_sch")
		(attr smd)
		(fp_rect
			(start -0.9656 0.4572)
			(end 0.9652 -0.4828)
			(stroke
				(width 0.05)
				(type solid)
			)
			(fill no)
			(layer "B.CrtYd")
		)
		(fp_line
			(start -0.5 0.25)
			(end 0.498 0.25)
			(stroke
				(width 0.15)
				(type solid)
			)
			(layer "B.Fab")
		)
		(fp_line
			(start 0.498 0.25)
			(end 0.498 -0.248)
			(stroke
				(width 0.15)
				(type solid)
			)
			(layer "B.Fab")
		)
		(fp_line
			(start -0.5 -0.248)
			(end -0.5 0.25)
			(stroke
				(width 0.15)
				(type solid)
			)
			(layer "B.Fab")
		)
		(fp_line
			(start 0.498 -0.248)
			(end -0.5 -0.248)
			(stroke
				(width 0.15)
				(type solid)
			)
			(layer "B.Fab")
		)
		(pad "1" smd roundrect
			(at -0.5 0 180)
			(size 0.6 0.6)
			(layers "B.Cu" "B.Mask" "B.Paste")
			(roundrect_rratio 0.25)
			(net 1 "GND")
			(pintype "passive")
		)
		(pad "2" smd roundrect
			(at 0.498 0 270)
			(size 0.6 0.6)
			(layers "B.Cu" "B.Mask" "B.Paste")
			(roundrect_rratio 0.25)
			(net 200 "+3V3")
			(pintype "passive")
		)
	)
)
